# T6G (Grand Teton) — schematic netlist excerpt (pin names and nets, part order shuffled) for the footprints in the layout excerpt that follows; sources: Cadence DE-HDL packaged netlist, KiCad conversion of 04192023_DAF0TMB3IC0_F0TG_MB_C_brd_V02_OCP.brd

C1882  Q_CAP  0.1UF 25V 10% X7R  pkg 0402  page 233 : A = P3V3_AUX ; B = GND

(kicad_pcb
	(version 20260206)
	(generator "pcbnew")
	(generator_version "10.0")
	(general
		(thickness 1.6)
		(legacy_teardrops no)
	)
	(paper "A4")
	(title_block
		(title "04192023_DAF0TMB3IC0_F0TG_MB_C_brd_V02_OCP.brd")
		(comment 1 "Grand Teton / footprints 545-545 of 8354")
	)
	(layers
		(0 "F.Cu" signal "TOP")
		(4 "In1.Cu" signal "GND")
		(6 "In2.Cu" signal "IN1")
		(8 "In3.Cu" signal "GND1")
		(10 "In4.Cu" signal "IN2")
		(12 "In5.Cu" signal "GND2")
		(14 "In6.Cu" signal "IN3")
		(16 "In7.Cu" signal "GND3")
		(18 "In8.Cu" signal "VCC")
		(20 "In9.Cu" signal "VCC1")
		(22 "In10.Cu" signal "GND4")
		(24 "In11.Cu" signal "IN4")
		(26 "In12.Cu" signal "GND5")
		(28 "In13.Cu" signal "IN5")
		(30 "In14.Cu" signal "GND6")
		(32 "In15.Cu" signal "IN6")
		(34 "In16.Cu" signal "GND7")
		(2 "B.Cu" signal "BOTTOM")
		(9 "F.Adhes" user "F.Adhesive")
		(11 "B.Adhes" user "B.Adhesive")
		(13 "F.Paste" user "Package Geometry/Pastemask Top")
		(15 "B.Paste" user "Package Geometry/Pastemask Bottom")
		(5 "F.SilkS" user "Ref Des/Silkscreen Top")
		(7 "B.SilkS" user "Ref Des/Silkscreen Bottom")
		(1 "F.Mask" user "Board Geometry/Soldermask Top")
		(3 "B.Mask" user "Board Geometry/Soldermask Bottom")
		(17 "Dwgs.User" user "User.Drawings")
		(19 "Cmts.User" user "User.Comments")
		(21 "Eco1.User" user "User.Eco1")
		(23 "Eco2.User" user "User.Eco2")
		(25 "Edge.Cuts" user "Board Geometry/Outline")
		(27 "Margin" user)
		(31 "F.CrtYd" user "Package Geometry/Place Bound Top")
		(29 "B.CrtYd" user "Package Geometry/Place Bound Bottom")
		(35 "F.Fab" user "Ref Des/Assembly Top")
		(33 "B.Fab" user "Ref Des/Assembly Bottom")
	)
	(footprint ""
		(layer "F.Cu")
		(at 30.075378 -132.788914 -90)
		(property "Reference" "C1882"
			(at 0 0 270)
			(layer "F.SilkS")
			(hide yes)
			(effects
				(font
					(size 1.27 1.27)
				)
			)
		)
		(property "Value" ""
			(at 0 0 270)
			(layer "F.Fab")
			(effects
				(font
					(size 1.27 1.27)
				)
			)
		)
		(duplicate_pad_numbers_are_jumpers no)
		(fp_line
			(start -0.7874 0.4064)
			(end -0.7874 -0.4064)
			(stroke
				(width 0.1524)
				(type default)
			)
			(layer "F.SilkS")
		)
		(fp_line
			(start 0.7874 0.4064)
			(end -0.7874 0.4064)
			(stroke
				(width 0.1524)
				(type default)
			)
			(layer "F.SilkS")
		)
		(fp_line
			(start -0.7874 -0.4064)
			(end 0.7874 -0.4064)
			(stroke
				(width 0.1524)
				(type default)
			)
			(layer "F.SilkS")
		)
		(fp_line
			(start 0.7874 -0.4064)
			(end 0.7874 0.4064)
			(stroke
				(width 0.1524)
				(type default)
			)
			(layer "F.SilkS")
		)
		(fp_line
			(start -0.67945 0.3048)
			(end -0.67945 -0.305054)
			(stroke
				(width 0.1)
				(type default)
			)
			(layer "F.Fab")
		)
		(fp_line
			(start -0.12065 0.3048)
			(end -0.67945 0.3048)
			(stroke
				(width 0.1)
				(type default)
			)
			(layer "F.Fab")
		)
		(fp_line
			(start 0.120396 0.3048)
			(end 0.120396 0.2794)
			(stroke
				(width 0.1)
				(type default)
			)
			(layer "F.Fab")
		)
		(fp_line
			(start 0.67945 0.3048)
			(end 0.120396 0.3048)
			(stroke
				(width 0.1)
				(type default)
			)
			(layer "F.Fab")
		)
		(fp_line
			(start -0.12065 0.2794)
			(end -0.12065 0.3048)
			(stroke
				(width 0.1)
				(type default)
			)
			(layer "F.Fab")
		)
		(fp_line
			(start 0.120396 0.2794)
			(end -0.12065 0.2794)
			(stroke
				(width 0.1)
				(type default)
			)
			(layer "F.Fab")
		)
		(fp_line
			(start -0.12065 -0.2794)
			(end 0.12065 -0.2794)
			(stroke
				(width 0.1)
				(type default)
			)
			(layer "F.Fab")
		)
		(fp_line
			(start 0.12065 -0.2794)
			(end 0.12065 -0.3048)
			(stroke
				(width 0.1)
				(type default)
			)
			(layer "F.Fab")
		)
		(fp_line
			(start 0.12065 -0.3048)
			(end 0.67945 -0.3048)
			(stroke
				(width 0.1)
				(type default)
			)
			(layer "F.Fab")
		)
		(fp_line
			(start 0.67945 -0.3048)
			(end 0.67945 0.3048)
			(stroke
				(width 0.1)
				(type default)
			)
			(layer "F.Fab")
		)
		(fp_line
			(start -0.67945 -0.305054)
			(end -0.12065 -0.305054)
			(stroke
				(width 0.1)
				(type default)
			)
			(layer "F.Fab")
		)
		(fp_line
			(start -0.12065 -0.305054)
			(end -0.12065 -0.2794)
			(stroke
				(width 0.1)
				(type default)
			)
			(layer "F.Fab")
		)
		(pad "1" smd circle
			(at -0.40005 0 270)
			(size 0 0)
			(layers "F.Cu" "F.Mask" "F.Paste")
			(net "P3V3_AUX")
		)
		(pad "2" smd circle
			(at 0.40005 0 270)
			(size 0 0)
			(layers "F.Cu" "F.Mask" "F.Paste")
			(net "GND")
		)
	)
)
